# S9S_MB_2U (Grand Teton) — schematic netlist excerpt (pin names and nets, part order shuffled) for the footprints in the layout excerpt that follows; sources: Cadence DE-HDL packaged netlist, KiCad conversion of 03242023_DA0F0TMBIJ0_F0T_Motherboard_J_brd_V01_OCP.brd

R4389  Q_RES  150 1% CHIP  pkg 0402LF  page 225 : A = PVNN_TERM_CPU0 ; B = H_CPU_ERR2_LVC1_R_N
C1240  Q_CAP  0.1UF 25V 10% X7R  pkg 0402  page 153 : A = P3V3_OCP_SFF ; B = GND

(kicad_pcb
	(version 20260206)
	(generator "pcbnew")
	(generator_version "10.0")
	(general
		(thickness 1.6)
		(legacy_teardrops no)
	)
	(paper "A4")
	(title_block
		(title "03242023_DA0F0TMBIJ0_F0T_Motherboard_J_brd_V01_OCP.brd")
		(comment 1 "Grand Teton / footprints 4583-4584 of 6105")
	)
	(layers
		(0 "F.Cu" signal "TOP")
		(4 "In1.Cu" signal "GND")
		(6 "In2.Cu" signal "IN1")
		(8 "In3.Cu" signal "GND1")
		(10 "In4.Cu" signal "IN2")
		(12 "In5.Cu" signal "GND2")
		(14 "In6.Cu" signal "IN3")
		(16 "In7.Cu" signal "GND3")
		(18 "In8.Cu" signal "VCC")
		(20 "In9.Cu" signal "VCC1")
		(22 "In10.Cu" signal "GND4")
		(24 "In11.Cu" signal "IN4")
		(26 "In12.Cu" signal "GND5")
		(28 "In13.Cu" signal "IN5")
		(30 "In14.Cu" signal "GND6")
		(32 "In15.Cu" signal "IN6")
		(34 "In16.Cu" signal "GND7")
		(2 "B.Cu" signal "BOTTOM")
		(9 "F.Adhes" user "F.Adhesive")
		(11 "B.Adhes" user "B.Adhesive")
		(13 "F.Paste" user "Package Geometry/Pastemask Top")
		(15 "B.Paste" user "Package Geometry/Pastemask Bottom")
		(5 "F.SilkS" user "Ref Des/Silkscreen Top")
		(7 "B.SilkS" user "Ref Des/Silkscreen Bottom")
		(1 "F.Mask" user "Board Geometry/Soldermask Top")
		(3 "B.Mask" user "Board Geometry/Soldermask Bottom")
		(17 "Dwgs.User" user "User.Drawings")
		(19 "Cmts.User" user "User.Comments")
		(21 "Eco1.User" user "User.Eco1")
		(23 "Eco2.User" user "User.Eco2")
		(25 "Edge.Cuts" user "Board Geometry/Outline")
		(27 "Margin" user)
		(31 "F.CrtYd" user "Package Geometry/Place Bound Top")
		(29 "B.CrtYd" user "Package Geometry/Place Bound Bottom")
		(35 "F.Fab" user "Ref Des/Assembly Top")
		(33 "B.Fab" user "Ref Des/Assembly Bottom")
	)
	(footprint ""
		(layer "B.Cu")
		(at 435.549802 -10.072116 180)
		(property "Reference" "C1240"
			(at 0 0 0)
			(layer "B.SilkS")
			(hide yes)
			(effects
				(font
					(size 1.27 1.27)
				)
				(justify mirror)
			)
		)
		(property "Value" ""
			(at 0 0 0)
			(layer "B.Fab")
			(effects
				(font
					(size 1.27 1.27)
				)
				(justify mirror)
			)
		)
		(duplicate_pad_numbers_are_jumpers no)
		(fp_line
			(start 0.7874 0.4064)
			(end 0.7874 -0.4064)
			(stroke
				(width 0.1524)
				(type default)
			)
			(layer "B.SilkS")
		)
		(fp_line
			(start 0.7874 -0.4064)
			(end -0.7874 -0.4064)
			(stroke
				(width 0.1524)
				(type default)
			)
			(layer "B.SilkS")
		)
		(fp_line
			(start -0.7874 0.4064)
			(end 0.7874 0.4064)
			(stroke
				(width 0.1524)
				(type default)
			)
			(layer "B.SilkS")
		)
		(fp_line
			(start -0.7874 -0.4064)
			(end -0.7874 0.4064)
			(stroke
				(width 0.1524)
				(type default)
			)
			(layer "B.SilkS")
		)
		(fp_line
			(start 0.67945 0.3048)
			(end 0.67945 -0.305054)
			(stroke
				(width 0.1)
				(type default)
			)
			(layer "B.Fab")
		)
		(fp_line
			(start 0.67945 -0.305054)
			(end 0.12065 -0.305054)
			(stroke
				(width 0.1)
				(type default)
			)
			(layer "B.Fab")
		)
		(fp_line
			(start 0.12065 0.3048)
			(end 0.67945 0.3048)
			(stroke
				(width 0.1)
				(type default)
			)
			(layer "B.Fab")
		)
		(fp_line
			(start 0.12065 0.2794)
			(end 0.12065 0.3048)
			(stroke
				(width 0.1)
				(type default)
			)
			(layer "B.Fab")
		)
		(fp_line
			(start 0.12065 -0.2794)
			(end -0.12065 -0.2794)
			(stroke
				(width 0.1)
				(type default)
			)
			(layer "B.Fab")
		)
		(fp_line
			(start 0.12065 -0.305054)
			(end 0.12065 -0.2794)
			(stroke
				(width 0.1)
				(type default)
			)
			(layer "B.Fab")
		)
		(fp_line
			(start -0.120396 0.3048)
			(end -0.120396 0.2794)
			(stroke
				(width 0.1)
				(type default)
			)
			(layer "B.Fab")
		)
		(fp_line
			(start -0.120396 0.2794)
			(end 0.12065 0.2794)
			(stroke
				(width 0.1)
				(type default)
			)
			(layer "B.Fab")
		)
		(fp_line
			(start -0.12065 -0.2794)
			(end -0.12065 -0.3048)
			(stroke
				(width 0.1)
				(type default)
			)
			(layer "B.Fab")
		)
		(fp_line
			(start -0.12065 -0.3048)
			(end -0.67945 -0.3048)
			(stroke
				(width 0.1)
				(type default)
			)
			(layer "B.Fab")
		)
		(fp_line
			(start -0.67945 0.3048)
			(end -0.120396 0.3048)
			(stroke
				(width 0.1)
				(type default)
			)
			(layer "B.Fab")
		)
		(fp_line
			(start -0.67945 -0.3048)
			(end -0.67945 0.3048)
			(stroke
				(width 0.1)
				(type default)
			)
			(layer "B.Fab")
		)
		(pad "1" smd circle
			(at 0.40005 0)
			(size 0 0)
			(layers "B.Cu" "B.Mask" "B.Paste")
			(net "P3V3_OCP_SFF")
		)
		(pad "2" smd circle
			(at -0.40005 0)
			(size 0 0)
			(layers "B.Cu" "B.Mask" "B.Paste")
			(net "GND")
		)
	)
	(footprint ""
		(layer "B.Cu")
		(at 317.276988 -191.619378 -90)
		(property "Reference" "R4389"
			(at 0 0 90)
			(layer "B.SilkS")
			(hide yes)
			(effects
				(font
					(size 1.27 1.27)
				)
				(justify mirror)
			)
		)
		(property "Value" ""
			(at 0 0 90)
			(layer "B.Fab")
			(effects
				(font
					(size 1.27 1.27)
				)
				(justify mirror)
			)
		)
		(duplicate_pad_numbers_are_jumpers no)
		(fp_line
			(start -0.7874 0.4064)
			(end 0.7874 0.4064)
			(stroke
				(width 0.1524)
				(type default)
			)
			(layer "B.SilkS")
		)
		(fp_line
			(start 0.7874 0.4064)
			(end 0.7874 -0.4064)
			(stroke
				(width 0.1524)
				(type default)
			)
			(layer "B.SilkS")
		)
		(fp_line
			(start -0.7874 -0.4064)
			(end -0.7874 0.4064)
			(stroke
				(width 0.1524)
				(type default)
			)
			(layer "B.SilkS")
		)
		(fp_line
			(start 0.7874 -0.4064)
			(end -0.7874 -0.4064)
			(stroke
				(width 0.1524)
				(type default)
			)
			(layer "B.SilkS")
		)
		(fp_line
			(start -0.67945 0.3048)
			(end -0.120396 0.3048)
			(stroke
				(width 0.1)
				(type default)
			)
			(layer "B.Fab")
		)
		(fp_line
			(start -0.120396 0.3048)
			(end -0.120396 0.2794)
			(stroke
				(width 0.1)
				(type default)
			)
			(layer "B.Fab")
		)
		(fp_line
			(start 0.12065 0.3048)
			(end 0.67945 0.3048)
			(stroke
				(width 0.1)
				(type default)
			)
			(layer "B.Fab")
		)
		(fp_line
			(start 0.67945 0.3048)
			(end 0.67945 -0.305054)
			(stroke
				(width 0.1)
				(type default)
			)
			(layer "B.Fab")
		)
		(fp_line
			(start -0.120396 0.2794)
			(end 0.12065 0.2794)
			(stroke
				(width 0.1)
				(type default)
			)
			(layer "B.Fab")
		)
		(fp_line
			(start 0.12065 0.2794)
			(end 0.12065 0.3048)
			(stroke
				(width 0.1)
				(type default)
			)
			(layer "B.Fab")
		)
		(fp_line
			(start -0.12065 -0.2794)
			(end -0.12065 -0.3048)
			(stroke
				(width 0.1)
				(type default)
			)
			(layer "B.Fab")
		)
		(fp_line
			(start 0.12065 -0.2794)
			(end -0.12065 -0.2794)
			(stroke
				(width 0.1)
				(type default)
			)
			(layer "B.Fab")
		)
		(fp_line
			(start -0.67945 -0.3048)
			(end -0.67945 0.3048)
			(stroke
				(width 0.1)
				(type default)
			)
			(layer "B.Fab")
		)
		(fp_line
			(start -0.12065 -0.3048)
			(end -0.67945 -0.3048)
			(stroke
				(width 0.1)
				(type default)
			)
			(layer "B.Fab")
		)
		(fp_line
			(start 0.12065 -0.305054)
			(end 0.12065 -0.2794)
			(stroke
				(width 0.1)
				(type default)
			)
			(layer "B.Fab")
		)
		(fp_line
			(start 0.67945 -0.305054)
			(end 0.12065 -0.305054)
			(stroke
				(width 0.1)
				(type default)
			)
			(layer "B.Fab")
		)
		(pad "1" smd circle
			(at 0.40005 0 90)
			(size 0 0)
			(layers "B.Cu" "B.Mask" "B.Paste")
			(net "PVNN_TERM_CPU0")
		)
		(pad "2" smd circle
			(at -0.40005 0 90)
			(size 0 0)
			(layers "B.Cu" "B.Mask" "B.Paste")
			(net "H_CPU_ERR2_LVC1_R_N")
		)
	)
)
